(kicad_pcb
	(version 20260206)
	(generator "pcbnew")
	(generator_version "10.0")
	(general
		(thickness 1.6)
		(legacy_teardrops no)
	)
	(paper "A4")
	(title_block
		(title "Bryce Canyon_R.DPB_16317-1_OCP.brd")
		(comment 1 "Bryce Canyon / footprints 1796-1802 of 2099")
	)
	(layers
		(0 "F.Cu" signal "TOP")
		(4 "In1.Cu" signal "L2GND")
		(6 "In2.Cu" signal "L3")
		(8 "In3.Cu" signal "L4VCC")
		(10 "In4.Cu" signal "L5VCC")
		(12 "In5.Cu" signal "L6")
		(14 "In6.Cu" signal "L7GND")
		(2 "B.Cu" signal "BOTTOM")
		(9 "F.Adhes" user "F.Adhesive")
		(11 "B.Adhes" user "B.Adhesive")
		(13 "F.Paste" user "Package Geometry/Pastemask Top")
		(15 "B.Paste" user "Package Geometry/Pastemask Bottom")
		(5 "F.SilkS" user "Ref Des/Silkscreen Top")
		(7 "B.SilkS" user "Ref Des/Silkscreen Bottom")
		(1 "F.Mask" user "Board Geometry/Soldermask Top")
		(3 "B.Mask" user "Board Geometry/Soldermask Bottom")
		(17 "Dwgs.User" user "User.Drawings")
		(19 "Cmts.User" user "User.Comments")
		(21 "Eco1.User" user "User.Eco1")
		(23 "Eco2.User" user "User.Eco2")
		(25 "Edge.Cuts" user "Board Geometry/Outline")
		(27 "Margin" user)
		(31 "F.CrtYd" user "Package Geometry/Place Bound Top")
		(29 "B.CrtYd" user "Package Geometry/Place Bound Bottom")
		(35 "F.Fab" user "Ref Des/Assembly Top")
		(33 "B.Fab" user "Ref Des/Assembly Bottom")
	)
	(footprint ""
		(layer "F.Cu")
		(at 317.975996 -376.60199)
		(property "Reference" "R1303"
			(at 0 0 0)
			(layer "F.SilkS")
			(hide yes)
			(effects
				(font
					(size 1.27 1.27)
				)
			)
		)
		(property "Value" "4K7R2F-GP"
			(at 0.064008 -3.993896 0)
			(unlocked yes)
			(layer "F.Fab")
			(hide yes)
			(effects
				(font
					(size 1.016 1.016)
					(thickness 0.1524)
				)
			)
		)
		(property "Device Type" "R402H16"
			(at 0.064008 -5.517896 0)
			(unlocked yes)
			(layer "F.Fab")
			(hide yes)
			(effects
				(font
					(size 1.016 1.016)
					(thickness 0.1524)
				)
			)
		)
		(duplicate_pad_numbers_are_jumpers no)
		(fp_line
			(start -0.508 -0.9398)
			(end -0.508 0.9398)
			(stroke
				(width 0.1524)
				(type default)
			)
			(layer "F.SilkS")
		)
		(fp_line
			(start 0.508 -0.9398)
			(end -0.508 -0.9398)
			(stroke
				(width 0.1524)
				(type default)
			)
			(layer "F.SilkS")
		)
		(fp_rect
			(start -0.508 0.9398)
			(end 0.508 -0.9398)
			(stroke
				(width 0)
				(type default)
			)
			(fill no)
			(layer "F.CrtYd")
		)
		(fp_rect
			(start -0.508 0.9398)
			(end 0.508 -0.9398)
			(stroke
				(width 0)
				(type default)
			)
			(fill no)
			(layer "F.Fab")
		)
		(pad "1" smd custom
			(at 0 -0.4445)
			(size 0.1397 0.1397)
			(layers "F.Cu" "F.Mask" "F.Paste")
			(net "FAN_BLUE_LED2")
			(options
				(clearance outline)
				(anchor circle)
			)
			(primitives
				(gr_poly
					(pts
						(arc
							(start -0.1778 -0.2794)
							(mid -0.249642 -0.249642)
							(end -0.2794 -0.1778)
						)
						(arc
							(start -0.2794 0.1778)
							(mid -0.249642 0.249642)
							(end -0.1778 0.2794)
						)
						(arc
							(start 0.1778 0.2794)
							(mid 0.249642 0.249642)
							(end 0.2794 0.1778)
						)
						(arc
							(start 0.2794 -0.1778)
							(mid 0.249642 -0.249642)
							(end 0.1778 -0.2794)
						)
					)
					(width 0)
					(fill yes)
				)
			)
		)
		(pad "2" smd custom
			(at 0 0.4445)
			(size 0.1397 0.1397)
			(layers "F.Cu" "F.Mask" "F.Paste")
			(net "FAN_LED2_D")
			(options
				(clearance outline)
				(anchor circle)
			)
			(primitives
				(gr_poly
					(pts
						(arc
							(start -0.1778 -0.2794)
							(mid -0.249642 -0.249642)
							(end -0.2794 -0.1778)
						)
						(arc
							(start -0.2794 0.1778)
							(mid -0.249642 0.249642)
							(end -0.1778 0.2794)
						)
						(arc
							(start 0.1778 0.2794)
							(mid 0.249642 0.249642)
							(end 0.2794 0.1778)
						)
						(arc
							(start 0.2794 -0.1778)
							(mid 0.249642 -0.249642)
							(end 0.1778 -0.2794)
						)
					)
					(width 0)
					(fill yes)
				)
			)
		)
	)
	(footprint ""
		(layer "F.Cu")
		(at 83.185 -262.001 -90)
		(property "Reference" "C57"
			(at 0 0 270)
			(layer "F.SilkS")
			(hide yes)
			(effects
				(font
					(size 1.27 1.27)
				)
			)
		)
		(property "Value" "SC10U16V6KX-2GP"
			(at -0.0762 -5.1308 270)
			(unlocked yes)
			(layer "F.Fab")
			(hide yes)
			(effects
				(font
					(size 1.016 1.016)
					(thickness 0.1524)
				)
			)
		)
		(property "Device Type" "C1206H71"
			(at -0.127 -6.6548 270)
			(unlocked yes)
			(layer "F.Fab")
			(hide yes)
			(effects
				(font
					(size 1.016 1.016)
					(thickness 0.1524)
				)
			)
		)
		(duplicate_pad_numbers_are_jumpers no)
		(fp_line
			(start -1.016 2.2352)
			(end -1.016 0.8382)
			(stroke
				(width 0.1524)
				(type default)
			)
			(layer "F.SilkS")
		)
		(fp_line
			(start 1.016 2.2352)
			(end -1.016 2.2352)
			(stroke
				(width 0.1524)
				(type default)
			)
			(layer "F.SilkS")
		)
		(fp_line
			(start 1.016 0.8382)
			(end 1.016 2.2352)
			(stroke
				(width 0.1524)
				(type default)
			)
			(layer "F.SilkS")
		)
		(fp_line
			(start -1.016 -0.8382)
			(end -1.016 -2.2352)
			(stroke
				(width 0.1524)
				(type default)
			)
			(layer "F.SilkS")
		)
		(fp_line
			(start -1.016 -2.2352)
			(end 1.016 -2.2352)
			(stroke
				(width 0.1524)
				(type default)
			)
			(layer "F.SilkS")
		)
		(fp_line
			(start 1.016 -2.2352)
			(end 1.016 -0.8382)
			(stroke
				(width 0.1524)
				(type default)
			)
			(layer "F.SilkS")
		)
		(fp_rect
			(start -1.0922 2.3114)
			(end 1.0922 -2.3114)
			(stroke
				(width 0)
				(type default)
			)
			(fill no)
			(layer "F.CrtYd")
		)
		(fp_poly
			(pts
				(xy 1.0922 -2.3114) (xy 1.0922 2.3114) (xy -1.0922 2.3114) (xy -1.0922 -2.3114)
			)
			(stroke
				(width 0)
				(type default)
			)
			(fill no)
			(layer "F.Fab")
		)
		(pad "1" smd rect
			(at 0 -1.397 270)
			(size 1.651 1.27)
			(layers "F.Cu" "F.Mask" "F.Paste")
			(net "P5V_HDD2")
		)
		(pad "2" smd rect
			(at 0 1.397 270)
			(size 1.651 1.27)
			(layers "F.Cu" "F.Mask" "F.Paste")
			(net "GND")
		)
	)
	(footprint ""
		(layer "F.Cu")
		(at 170.119294 -369.697 180)
		(property "Reference" "C569"
			(at 0 0 180)
			(layer "F.SilkS")
			(hide yes)
			(effects
				(font
					(size 1.27 1.27)
				)
			)
		)
		(property "Value" "SCD015U25V2KX-GP"
			(at 1.1811 -2.7051 180)
			(unlocked yes)
			(layer "F.Fab")
			(hide yes)
			(effects
				(font
					(size 1.016 1.016)
					(thickness 0.1524)
				)
			)
		)
		(property "Device Type" "C402H22"
			(at 1.1811 -4.2291 180)
			(unlocked yes)
			(layer "F.Fab")
			(hide yes)
			(effects
				(font
					(size 1.016 1.016)
					(thickness 0.1524)
				)
			)
		)
		(duplicate_pad_numbers_are_jumpers no)
		(fp_rect
			(start -0.4318 0.9525)
			(end 0.4318 -0.9525)
			(stroke
				(width 0)
				(type default)
			)
			(fill no)
			(layer "F.CrtYd")
		)
		(fp_rect
			(start -0.4318 0.9525)
			(end 0.4318 -0.9525)
			(stroke
				(width 0)
				(type default)
			)
			(fill no)
			(layer "F.Fab")
		)
		(pad "1" smd custom
			(at 0 -0.4445 180)
			(size 0.1524 0.1524)
			(layers "F.Cu" "F.Mask" "F.Paste")
			(net "MB0_HS_SENSE_P")
			(options
				(clearance outline)
				(anchor circle)
			)
			(primitives
				(gr_poly
					(pts
						(arc
							(start 0.3048 -0.2032)
							(mid 0.275042 -0.275042)
							(end 0.2032 -0.3048)
						)
						(arc
							(start -0.2032 -0.3048)
							(mid -0.275042 -0.275042)
							(end -0.3048 -0.2032)
						)
						(arc
							(start -0.3048 0.2032)
							(mid -0.275042 0.275042)
							(end -0.2032 0.3048)
						)
						(arc
							(start 0.2032 0.3048)
							(mid 0.275042 0.275042)
							(end 0.3048 0.2032)
						)
					)
					(width 0)
					(fill yes)
				)
			)
		)
		(pad "2" smd custom
			(at 0 0.4445 180)
			(size 0.1524 0.1524)
			(layers "F.Cu" "F.Mask" "F.Paste")
			(net "MB0_HS_SENSE_N")
			(options
				(clearance outline)
				(anchor circle)
			)
			(primitives
				(gr_poly
					(pts
						(arc
							(start 0.3048 -0.2032)
							(mid 0.275042 -0.275042)
							(end 0.2032 -0.3048)
						)
						(arc
							(start -0.2032 -0.3048)
							(mid -0.275042 -0.275042)
							(end -0.3048 -0.2032)
						)
						(arc
							(start -0.3048 0.2032)
							(mid -0.275042 0.275042)
							(end -0.2032 0.3048)
						)
						(arc
							(start 0.2032 0.3048)
							(mid 0.275042 0.275042)
							(end 0.3048 0.2032)
						)
					)
					(width 0)
					(fill yes)
				)
			)
		)
	)
	(footprint ""
		(layer "F.Cu")
		(at 455.311002 -229.49535 180)
		(property "Reference" "R1152"
			(at 0 0 180)
			(layer "F.SilkS")
			(hide yes)
			(effects
				(font
					(size 1.27 1.27)
				)
			)
		)
		(property "Value" "619KR2F-GP"
			(at 0.064008 -3.993896 180)
			(unlocked yes)
			(layer "F.Fab")
			(hide yes)
			(effects
				(font
					(size 1.016 1.016)
					(thickness 0.1524)
				)
			)
		)
		(property "Device Type" "R402H16"
			(at 0.064008 -5.517896 180)
			(unlocked yes)
			(layer "F.Fab")
			(hide yes)
			(effects
				(font
					(size 1.016 1.016)
					(thickness 0.1524)
				)
			)
		)
		(duplicate_pad_numbers_are_jumpers no)
		(fp_line
			(start 0.508 -0.9398)
			(end -0.508 -0.9398)
			(stroke
				(width 0.1524)
				(type default)
			)
			(layer "F.SilkS")
		)
		(fp_line
			(start -0.508 -0.9398)
			(end -0.508 0.9398)
			(stroke
				(width 0.1524)
				(type default)
			)
			(layer "F.SilkS")
		)
		(fp_rect
			(start -0.508 0.9398)
			(end 0.508 -0.9398)
			(stroke
				(width 0)
				(type default)
			)
			(fill no)
			(layer "F.CrtYd")
		)
		(fp_rect
			(start -0.508 0.9398)
			(end 0.508 -0.9398)
			(stroke
				(width 0)
				(type default)
			)
			(fill no)
			(layer "F.Fab")
		)
		(pad "1" smd custom
			(at 0 -0.4445 180)
			(size 0.1397 0.1397)
			(layers "F.Cu" "F.Mask" "F.Paste")
			(net "P5V_B_3_RF")
			(options
				(clearance outline)
				(anchor circle)
			)
			(primitives
				(gr_poly
					(pts
						(arc
							(start -0.1778 -0.2794)
							(mid -0.249642 -0.249642)
							(end -0.2794 -0.1778)
						)
						(arc
							(start -0.2794 0.1778)
							(mid -0.249642 0.249642)
							(end -0.1778 0.2794)
						)
						(arc
							(start 0.1778 0.2794)
							(mid 0.249642 0.249642)
							(end 0.2794 0.1778)
						)
						(arc
							(start 0.2794 -0.1778)
							(mid 0.249642 -0.249642)
							(end 0.1778 -0.2794)
						)
					)
					(width 0)
					(fill yes)
				)
			)
		)
		(pad "2" smd custom
			(at 0 0.4445 180)
			(size 0.1397 0.1397)
			(layers "F.Cu" "F.Mask" "F.Paste")
			(net "AGND_P5V_B_3")
			(options
				(clearance outline)
				(anchor circle)
			)
			(primitives
				(gr_poly
					(pts
						(arc
							(start -0.1778 -0.2794)
							(mid -0.249642 -0.249642)
							(end -0.2794 -0.1778)
						)
						(arc
							(start -0.2794 0.1778)
							(mid -0.249642 0.249642)
							(end -0.1778 0.2794)
						)
						(arc
							(start 0.1778 0.2794)
							(mid 0.249642 0.249642)
							(end 0.2794 0.1778)
						)
						(arc
							(start 0.2794 -0.1778)
							(mid 0.249642 -0.249642)
							(end 0.1778 -0.2794)
						)
					)
					(width 0)
					(fill yes)
				)
			)
		)
	)
	(footprint ""
		(layer "F.Cu")
		(at 346.075 -99.187)
		(property "Reference" "R434"
			(at 0 0 0)
			(layer "F.SilkS")
			(hide yes)
			(effects
				(font
					(size 1.27 1.27)
				)
			)
		)
		(property "Value" "130R3F-GP"
			(at -0.0254 -2.5146 0)
			(unlocked yes)
			(layer "F.Fab")
			(hide yes)
			(effects
				(font
					(size 1.016 1.016)
					(thickness 0.1524)
				)
			)
		)
		(property "Device Type" "R603H22"
			(at -0.0254 -4.0386 0)
			(unlocked yes)
			(layer "F.Fab")
			(hide yes)
			(effects
				(font
					(size 1.016 1.016)
					(thickness 0.1524)
				)
			)
		)
		(duplicate_pad_numbers_are_jumpers no)
		(fp_line
			(start -0.4826 0)
			(end -0.2032 0)
			(stroke
				(width 0.2032)
				(type default)
			)
			(layer "F.SilkS")
		)
		(fp_line
			(start 0.2032 0)
			(end 0.4826 0)
			(stroke
				(width 0.2032)
				(type default)
			)
			(layer "F.SilkS")
		)
		(fp_rect
			(start -0.5842 1.3335)
			(end 0.5842 -1.3335)
			(stroke
				(width 0)
				(type default)
			)
			(fill no)
			(layer "F.CrtYd")
		)
		(fp_rect
			(start -0.5842 1.3335)
			(end 0.5842 -1.3335)
			(stroke
				(width 0)
				(type default)
			)
			(fill no)
			(layer "F.Fab")
		)
		(pad "1" smd custom
			(at 0 -0.762)
			(size 0.2159 0.2159)
			(layers "F.Cu" "F.Mask" "F.Paste")
			(net "P5V_B_3")
			(options
				(clearance outline)
				(anchor circle)
			)
			(primitives
				(gr_poly
					(pts
						(arc
							(start -0.3302 -0.4318)
							(mid -0.402042 -0.402042)
							(end -0.4318 -0.3302)
						)
						(arc
							(start -0.4318 0.3302)
							(mid -0.402042 0.402042)
							(end -0.3302 0.4318)
						)
						(arc
							(start 0.3302 0.4318)
							(mid 0.402042 0.402042)
							(end 0.4318 0.3302)
						)
						(arc
							(start 0.4318 -0.3302)
							(mid 0.402042 -0.402042)
							(end 0.3302 -0.4318)
						)
					)
					(width 0)
					(fill yes)
				)
			)
		)
		(pad "2" smd custom
			(at 0 0.762)
			(size 0.2159 0.2159)
			(layers "F.Cu" "F.Mask" "F.Paste")
			(net "FLT_HDD19")
			(options
				(clearance outline)
				(anchor circle)
			)
			(primitives
				(gr_poly
					(pts
						(arc
							(start -0.3302 -0.4318)
							(mid -0.402042 -0.402042)
							(end -0.4318 -0.3302)
						)
						(arc
							(start -0.4318 0.3302)
							(mid -0.402042 0.402042)
							(end -0.3302 0.4318)
						)
						(arc
							(start 0.3302 0.4318)
							(mid 0.402042 0.402042)
							(end 0.4318 0.3302)
						)
						(arc
							(start 0.4318 -0.3302)
							(mid 0.402042 -0.402042)
							(end 0.3302 -0.4318)
						)
					)
					(width 0)
					(fill yes)
				)
			)
		)
	)
	(footprint ""
		(layer "F.Cu")
		(at 111.8616 -9.525 180)
		(property "Reference" "C390"
			(at 0 0 180)
			(layer "F.SilkS")
			(hide yes)
			(effects
				(font
					(size 1.27 1.27)
				)
			)
		)
		(property "Value" "SCD033U25V2KX-GP"
			(at 1.1811 -2.7051 180)
			(unlocked yes)
			(layer "F.Fab")
			(hide yes)
			(effects
				(font
					(size 1.016 1.016)
					(thickness 0.1524)
				)
			)
		)
		(property "Device Type" "C402H22"
			(at 1.1811 -4.2291 180)
			(unlocked yes)
			(layer "F.Fab")
			(hide yes)
			(effects
				(font
					(size 1.016 1.016)
					(thickness 0.1524)
				)
			)
		)
		(duplicate_pad_numbers_are_jumpers no)
		(fp_rect
			(start -0.4318 0.9525)
			(end 0.4318 -0.9525)
			(stroke
				(width 0)
				(type default)
			)
			(fill no)
			(layer "F.CrtYd")
		)
		(fp_rect
			(start -0.4318 0.9525)
			(end 0.4318 -0.9525)
			(stroke
				(width 0)
				(type default)
			)
			(fill no)
			(layer "F.Fab")
		)
		(pad "1" smd custom
			(at 0 -0.4445 180)
			(size 0.1524 0.1524)
			(layers "F.Cu" "F.Mask" "F.Paste")
			(net "P12V_B")
			(options
				(clearance outline)
				(anchor circle)
			)
			(primitives
				(gr_poly
					(pts
						(arc
							(start 0.3048 -0.2032)
							(mid 0.275042 -0.275042)
							(end 0.2032 -0.3048)
						)
						(arc
							(start -0.2032 -0.3048)
							(mid -0.275042 -0.275042)
							(end -0.3048 -0.2032)
						)
						(arc
							(start -0.3048 0.2032)
							(mid -0.275042 0.275042)
							(end -0.2032 0.3048)
						)
						(arc
							(start 0.2032 0.3048)
							(mid 0.275042 0.275042)
							(end 0.3048 0.2032)
						)
					)
					(width 0)
					(fill yes)
				)
			)
		)
		(pad "2" smd custom
			(at 0 0.4445 180)
			(size 0.1524 0.1524)
			(layers "F.Cu" "F.Mask" "F.Paste")
			(net "SW_HDD_N27")
			(options
				(clearance outline)
				(anchor circle)
			)
			(primitives
				(gr_poly
					(pts
						(arc
							(start 0.3048 -0.2032)
							(mid 0.275042 -0.275042)
							(end 0.2032 -0.3048)
						)
						(arc
							(start -0.2032 -0.3048)
							(mid -0.275042 -0.275042)
							(end -0.3048 -0.2032)
						)
						(arc
							(start -0.3048 0.2032)
							(mid -0.275042 0.275042)
							(end -0.2032 0.3048)
						)
						(arc
							(start 0.2032 0.3048)
							(mid 0.275042 0.275042)
							(end 0.3048 0.2032)
						)
					)
					(width 0)
					(fill yes)
				)
			)
		)
	)
	(footprint ""
		(layer "F.Cu")
		(at 326.738996 -373.761 -90)
		(property "Reference" "R946"
			(at 0 0 270)
			(layer "F.SilkS")
			(hide yes)
			(effects
				(font
					(size 1.27 1.27)
				)
			)
		)
		(property "Value" "0R2J-2-GP"
			(at 0.064008 -3.993896 270)
			(unlocked yes)
			(layer "F.Fab")
			(hide yes)
			(effects
				(font
					(size 1.016 1.016)
					(thickness 0.1524)
				)
			)
		)
		(property "Device Type" "R402H16"
			(at 0.064008 -5.517896 270)
			(unlocked yes)
			(layer "F.Fab")
			(hide yes)
			(effects
				(font
					(size 1.016 1.016)
					(thickness 0.1524)
				)
			)
		)
		(duplicate_pad_numbers_are_jumpers no)
		(fp_line
			(start -0.508 -0.9398)
			(end -0.508 0.9398)
			(stroke
				(width 0.1524)
				(type default)
			)
			(layer "F.SilkS")
		)
		(fp_line
			(start 0.508 -0.9398)
			(end -0.508 -0.9398)
			(stroke
				(width 0.1524)
				(type default)
			)
			(layer "F.SilkS")
		)
		(fp_rect
			(start -0.508 0.9398)
			(end 0.508 -0.9398)
			(stroke
				(width 0)
				(type default)
			)
			(fill no)
			(layer "F.CrtYd")
		)
		(fp_rect
			(start -0.508 0.9398)
			(end 0.508 -0.9398)
			(stroke
				(width 0)
				(type default)
			)
			(fill no)
			(layer "F.Fab")
		)
		(pad "1" smd custom
			(at 0 -0.4445 270)
			(size 0.1397 0.1397)
			(layers "F.Cu" "F.Mask" "F.Paste")
			(net "FAN_2_PWM")
			(options
				(clearance outline)
				(anchor circle)
			)
			(primitives
				(gr_poly
					(pts
						(arc
							(start -0.1778 -0.2794)
							(mid -0.249642 -0.249642)
							(end -0.2794 -0.1778)
						)
						(arc
							(start -0.2794 0.1778)
							(mid -0.249642 0.249642)
							(end -0.1778 0.2794)
						)
						(arc
							(start 0.1778 0.2794)
							(mid 0.249642 0.249642)
							(end 0.2794 0.1778)
						)
						(arc
							(start 0.2794 -0.1778)
							(mid 0.249642 -0.249642)
							(end 0.1778 -0.2794)
						)
					)
					(width 0)
					(fill yes)
				)
			)
		)
		(pad "2" smd custom
			(at 0 0.4445 270)
			(size 0.1397 0.1397)
			(layers "F.Cu" "F.Mask" "F.Paste")
			(net "PWM_OUT_FAN2")
			(options
				(clearance outline)
				(anchor circle)
			)
			(primitives
				(gr_poly
					(pts
						(arc
							(start -0.1778 -0.2794)
							(mid -0.249642 -0.249642)
							(end -0.2794 -0.1778)
						)
						(arc
							(start -0.2794 0.1778)
							(mid -0.249642 0.249642)
							(end -0.1778 0.2794)
						)
						(arc
							(start 0.1778 0.2794)
							(mid 0.249642 0.249642)
							(end 0.2794 0.1778)
						)
						(arc
							(start 0.2794 -0.1778)
							(mid 0.249642 -0.249642)
							(end 0.1778 -0.2794)
						)
					)
					(width 0)
					(fill yes)
				)
			)
		)
	)
)
